# BASEBOARD_FAB2 (Tioga Pass) — schematic netlist excerpt (pin names and nets, part order shuffled) for the footprints in the layout excerpt that follows; sources: Cadence DE-HDL packaged netlist, KiCad conversion of Wiwynn_Tioga_Pass_MB.brd

R1G6  RES  2.26K 1.0% CHIP  pkg 0402  page 223 : A = P3V3_STBY ; B = PWRGD_PVDDQ_GHJ
R4D70  RES  4.75K 1% CHIP  pkg 0402  page 102 : A = P3V3 ; B = FM_CPU0_MCP_CLK_EN_N
R1U53  RES  0.0 5% CHIP  pkg 0402  page 152 : A = H_CPU1_MEMGHJ_MEMHOT_G_N ; B = H_CPU1_MEMGHJ_MEMHOT_G_R_N

(kicad_pcb
	(version 20260206)
	(generator "pcbnew")
	(generator_version "10.0")
	(general
		(thickness 1.6)
		(legacy_teardrops no)
	)
	(paper "A4")
	(title_block
		(title "Wiwynn_Tioga_Pass_MB.brd")
		(comment 1 "Tioga Pass / footprints 747-749 of 4770")
	)
	(layers
		(0 "F.Cu" signal "TOP")
		(4 "In1.Cu" signal "L2GND")
		(6 "In2.Cu" signal "L3")
		(8 "In3.Cu" signal "L4GND")
		(10 "In4.Cu" signal "L5")
		(12 "In5.Cu" signal "L6GND")
		(14 "In6.Cu" signal "L7VCC")
		(16 "In7.Cu" signal "L8VCC")
		(18 "In8.Cu" signal "L9GND")
		(20 "In9.Cu" signal "L10")
		(22 "In10.Cu" signal "L11GND")
		(24 "In11.Cu" signal "L12")
		(26 "In12.Cu" signal "L13GND")
		(2 "B.Cu" signal "BOTTOM")
		(9 "F.Adhes" user "F.Adhesive")
		(11 "B.Adhes" user "B.Adhesive")
		(13 "F.Paste" user "Package Geometry/Pastemask Top")
		(15 "B.Paste" user "Package Geometry/Pastemask Bottom")
		(5 "F.SilkS" user "Ref Des/Silkscreen Top")
		(7 "B.SilkS" user "Ref Des/Silkscreen Bottom")
		(1 "F.Mask" user "Board Geometry/Soldermask Top")
		(3 "B.Mask" user "Board Geometry/Soldermask Bottom")
		(17 "Dwgs.User" user "User.Drawings")
		(19 "Cmts.User" user "User.Comments")
		(21 "Eco1.User" user "User.Eco1")
		(23 "Eco2.User" user "User.Eco2")
		(25 "Edge.Cuts" user "Board Geometry/Outline")
		(27 "Margin" user)
		(31 "F.CrtYd" user "Package Geometry/Place Bound Top")
		(29 "B.CrtYd" user "Package Geometry/Place Bound Bottom")
		(35 "F.Fab" user "Ref Des/Assembly Top")
		(33 "B.Fab" user "Ref Des/Assembly Bottom")
	)
	(footprint ""
		(layer "F.Cu")
		(at 12.7127 -5.197856 -90)
		(property "Reference" "R1G6"
			(at -0.8382 -0.67818 270)
			(unlocked yes)
			(layer "F.SilkS")
			(effects
				(font
					(size 0.4064 0.254)
					(thickness 0.1524)
				)
				(justify left)
			)
		)
		(property "Value" ""
			(at 0 0 270)
			(layer "F.Fab")
			(effects
				(font
					(size 1.27 1.27)
				)
			)
		)
		(duplicate_pad_numbers_are_jumpers no)
		(fp_poly
			(pts
				(xy -0.2794 -0.1016) (xy 0.2794 -0.1016) (xy 0.2794 0.9906) (xy -0.2794 0.9906)
			)
			(stroke
				(width 0)
				(type default)
			)
			(fill no)
			(layer "F.CrtYd")
		)
		(fp_line
			(start -0.2794 0.9906)
			(end 0.2794 0.9906)
			(stroke
				(width 0.1)
				(type default)
			)
			(layer "F.Fab")
		)
		(fp_line
			(start 0.2794 0.9906)
			(end 0.2794 -0.1016)
			(stroke
				(width 0.1)
				(type default)
			)
			(layer "F.Fab")
		)
		(fp_line
			(start -0.2794 -0.1016)
			(end -0.2794 0.9906)
			(stroke
				(width 0.1)
				(type default)
			)
			(layer "F.Fab")
		)
		(fp_line
			(start 0.2794 -0.1016)
			(end -0.2794 -0.1016)
			(stroke
				(width 0.1)
				(type default)
			)
			(layer "F.Fab")
		)
		(pad "1" smd rect
			(at 0 0 270)
			(size 0.508 0.508)
			(layers "F.Cu" "F.Mask" "F.Paste")
			(net "P3V3_STBY")
		)
		(pad "2" smd rect
			(at 0 0.889 270)
			(size 0.508 0.508)
			(layers "F.Cu" "F.Mask" "F.Paste")
			(net "PWRGD_PVDDQ_GHJ")
		)
		(zone
			(layer "F.Cu")
			(hatch none 0.5)
			(connect_pads
				(clearance 0)
			)
			(min_thickness 0.25)
			(keepout
				(tracks not_allowed)
				(vias allowed)
				(pads allowed)
				(copperpour not_allowed)
				(footprints allowed)
			)
			(placement
				(enabled no)
				(sheetname "")
			)
			(fill
				(thermal_gap 0.5)
				(thermal_bridge_width 0.5)
				(island_removal_mode 0)
			)
			(polygon
				(pts
					(xy 12.0777 -5.451856) (xy 12.0777 -4.943856) (xy 12.4587 -4.943856) (xy 12.4587 -5.451856)
				)
			)
		)
		(zone
			(layer "F.Cu")
			(hatch none 0.5)
			(connect_pads
				(clearance 0)
			)
			(min_thickness 0.25)
			(keepout
				(tracks allowed)
				(vias not_allowed)
				(pads allowed)
				(copperpour not_allowed)
				(footprints allowed)
			)
			(placement
				(enabled no)
				(sheetname "")
			)
			(fill
				(thermal_gap 0.5)
				(thermal_bridge_width 0.5)
				(island_removal_mode 0)
			)
			(polygon
				(pts
					(xy 12.4587 -5.451856) (xy 12.4587 -4.943856) (xy 12.0777 -4.943856) (xy 12.0777 -5.451856)
				)
			)
		)
	)
	(footprint ""
		(layer "F.Cu")
		(at 179.07 -84.328 180)
		(property "Reference" "R4D70"
			(at 0 0 180)
			(layer "F.SilkS")
			(hide yes)
			(effects
				(font
					(size 1.27 1.27)
				)
			)
		)
		(property "Value" ""
			(at 0 0 180)
			(layer "F.Fab")
			(effects
				(font
					(size 1.27 1.27)
				)
			)
		)
		(duplicate_pad_numbers_are_jumpers no)
		(fp_poly
			(pts
				(xy -0.2794 -0.1016) (xy 0.2794 -0.1016) (xy 0.2794 0.9906) (xy -0.2794 0.9906)
			)
			(stroke
				(width 0)
				(type default)
			)
			(fill no)
			(layer "F.CrtYd")
		)
		(fp_line
			(start 0.2794 0.9906)
			(end 0.2794 -0.1016)
			(stroke
				(width 0.1)
				(type default)
			)
			(layer "F.Fab")
		)
		(fp_line
			(start 0.2794 -0.1016)
			(end -0.2794 -0.1016)
			(stroke
				(width 0.1)
				(type default)
			)
			(layer "F.Fab")
		)
		(fp_line
			(start -0.2794 0.9906)
			(end 0.2794 0.9906)
			(stroke
				(width 0.1)
				(type default)
			)
			(layer "F.Fab")
		)
		(fp_line
			(start -0.2794 -0.1016)
			(end -0.2794 0.9906)
			(stroke
				(width 0.1)
				(type default)
			)
			(layer "F.Fab")
		)
		(pad "1" smd rect
			(at 0 0 180)
			(size 0.508 0.508)
			(layers "F.Cu" "F.Mask" "F.Paste")
			(net "P3V3")
		)
		(pad "2" smd rect
			(at 0 0.889 180)
			(size 0.508 0.508)
			(layers "F.Cu" "F.Mask" "F.Paste")
			(net "FM_CPU0_MCP_CLK_EN_N")
		)
		(zone
			(layer "F.Cu")
			(hatch none 0.5)
			(connect_pads
				(clearance 0)
			)
			(min_thickness 0.25)
			(keepout
				(tracks not_allowed)
				(vias allowed)
				(pads allowed)
				(copperpour not_allowed)
				(footprints allowed)
			)
			(placement
				(enabled no)
				(sheetname "")
			)
			(fill
				(thermal_gap 0.5)
				(thermal_bridge_width 0.5)
				(island_removal_mode 0)
			)
			(polygon
				(pts
					(xy 179.324 -84.963) (xy 178.816 -84.963) (xy 178.816 -84.582) (xy 179.324 -84.582)
				)
			)
		)
		(zone
			(layer "F.Cu")
			(hatch none 0.5)
			(connect_pads
				(clearance 0)
			)
			(min_thickness 0.25)
			(keepout
				(tracks allowed)
				(vias not_allowed)
				(pads allowed)
				(copperpour not_allowed)
				(footprints allowed)
			)
			(placement
				(enabled no)
				(sheetname "")
			)
			(fill
				(thermal_gap 0.5)
				(thermal_bridge_width 0.5)
				(island_removal_mode 0)
			)
			(polygon
				(pts
					(xy 179.324 -84.582) (xy 178.816 -84.582) (xy 178.816 -84.963) (xy 179.324 -84.963)
				)
			)
		)
	)
	(footprint ""
		(layer "F.Cu")
		(at 438.4675 -15.367 90)
		(property "Reference" "R1U53"
			(at 0 0 90)
			(layer "F.SilkS")
			(hide yes)
			(effects
				(font
					(size 1.27 1.27)
				)
			)
		)
		(property "Value" ""
			(at 0 0 90)
			(layer "F.Fab")
			(effects
				(font
					(size 1.27 1.27)
				)
			)
		)
		(duplicate_pad_numbers_are_jumpers no)
		(fp_poly
			(pts
				(xy -0.2794 -0.1016) (xy 0.2794 -0.1016) (xy 0.2794 0.9906) (xy -0.2794 0.9906)
			)
			(stroke
				(width 0)
				(type default)
			)
			(fill no)
			(layer "F.CrtYd")
		)
		(fp_line
			(start 0.2794 -0.1016)
			(end -0.2794 -0.1016)
			(stroke
				(width 0.1)
				(type default)
			)
			(layer "F.Fab")
		)
		(fp_line
			(start -0.2794 -0.1016)
			(end -0.2794 0.9906)
			(stroke
				(width 0.1)
				(type default)
			)
			(layer "F.Fab")
		)
		(fp_line
			(start 0.2794 0.9906)
			(end 0.2794 -0.1016)
			(stroke
				(width 0.1)
				(type default)
			)
			(layer "F.Fab")
		)
		(fp_line
			(start -0.2794 0.9906)
			(end 0.2794 0.9906)
			(stroke
				(width 0.1)
				(type default)
			)
			(layer "F.Fab")
		)
		(pad "1" smd rect
			(at 0 0 90)
			(size 0.508 0.508)
			(layers "F.Cu" "F.Mask" "F.Paste")
			(net "H_CPU1_MEMGHJ_MEMHOT_G_N")
		)
		(pad "2" smd rect
			(at 0 0.889 90)
			(size 0.508 0.508)
			(layers "F.Cu" "F.Mask" "F.Paste")
			(net "H_CPU1_MEMGHJ_MEMHOT_G_R_N")
		)
		(zone
			(layer "F.Cu")
			(hatch none 0.5)
			(connect_pads
				(clearance 0)
			)
			(min_thickness 0.25)
			(keepout
				(tracks allowed)
				(vias not_allowed)
				(pads allowed)
				(copperpour not_allowed)
				(footprints allowed)
			)
			(placement
				(enabled no)
				(sheetname "")
			)
			(fill
				(thermal_gap 0.5)
				(thermal_bridge_width 0.5)
				(island_removal_mode 0)
			)
			(polygon
				(pts
					(xy 438.7215 -15.113) (xy 438.7215 -15.621) (xy 439.1025 -15.621) (xy 439.1025 -15.113)
				)
			)
		)
		(zone
			(layer "F.Cu")
			(hatch none 0.5)
			(connect_pads
				(clearance 0)
			)
			(min_thickness 0.25)
			(keepout
				(tracks not_allowed)
				(vias allowed)
				(pads allowed)
				(copperpour not_allowed)
				(footprints allowed)
			)
			(placement
				(enabled no)
				(sheetname "")
			)
			(fill
				(thermal_gap 0.5)
				(thermal_bridge_width 0.5)
				(island_removal_mode 0)
			)
			(polygon
				(pts
					(xy 439.1025 -15.113) (xy 439.1025 -15.621) (xy 438.7215 -15.621) (xy 438.7215 -15.113)
				)
			)
		)
	)
)
